(kicad_pcb
	(version 20260206)
	(generator "pcbnew")
	(generator_version "10.0")
	(general
		(thickness 1.21888)
		(legacy_teardrops no)
	)
	(paper "A4")
	(title_block
		(title "timecard-v7 — TimeCard-DC-V7_EXP.PcbDoc")
		(comment 1 "Time Appliance Project (Time Card) / footprints 22-34 of 160")
	)
	(layers
		(0 "F.Cu" signal "TOP")
		(4 "In1.Cu" signal "SGND")
		(6 "In2.Cu" signal "IN1")
		(8 "In3.Cu" signal "IN2")
		(10 "In4.Cu" signal "SGND1")
		(2 "B.Cu" signal "BOTTOM")
		(9 "F.Adhes" user "F.Adhesive")
		(11 "B.Adhes" user "B.Adhesive")
		(13 "F.Paste" user "Top Paste")
		(15 "B.Paste" user "Bottom Paste")
		(5 "F.SilkS" user "Top Overlay")
		(7 "B.SilkS" user "Bottom Overlay")
		(1 "F.Mask" user "Top Solder")
		(3 "B.Mask" user "Bottom Solder")
		(17 "Dwgs.User" user "User.Drawings")
		(19 "Cmts.User" user "User.Comments")
		(21 "Eco1.User" user "User.Eco1")
		(23 "Eco2.User" user "User.Eco2")
		(25 "Edge.Cuts" user)
		(27 "Margin" user)
		(31 "F.CrtYd" user "Top Courtyard")
		(29 "B.CrtYd" user "Bottom Courtyard")
		(35 "F.Fab" user "Top Component Center")
		(33 "B.Fab" user "Bottom Component Center")
	)
	(footprint "Miscellaneous Connectors:HDR1X4"
		(layer "F.Cu")
		(at 106.9061 85.6162 180)
		(property "Reference" "P1"
			(at 10.448798 0.16477 90)
			(unlocked yes)
			(layer "F.SilkS")
			(effects
				(font
					(size 1.524 1.524)
					(thickness 0.254)
				)
			)
		)
		(property "Value" "AUX Sensor"
			(at -2.937002 6.38576 90)
			(unlocked yes)
			(layer "F.SilkS")
			(hide yes)
			(effects
				(font
					(size 1.524 1.524)
					(thickness 0.254)
				)
			)
		)
		(sheetname "GPS_IMU_SENSORS")
		(sheetfile "GPS_IMU_SENSORS.kicad_sch")
		(duplicate_pad_numbers_are_jumpers no)
		(fp_line
			(start 8.89 1.27)
			(end -1.27 1.27)
			(stroke
				(width 0.2)
				(type solid)
			)
			(layer "F.SilkS")
		)
		(fp_line
			(start 8.89 -1.27)
			(end 8.89 1.27)
			(stroke
				(width 0.2)
				(type solid)
			)
			(layer "F.SilkS")
		)
		(fp_line
			(start 8.89 -1.27)
			(end -1.27 -1.27)
			(stroke
				(width 0.2)
				(type solid)
			)
			(layer "F.SilkS")
		)
		(fp_line
			(start -1.27 -1.27)
			(end -1.27 1.27)
			(stroke
				(width 0.2)
				(type solid)
			)
			(layer "F.SilkS")
		)
		(pad "1" thru_hole rect
			(at 0 0 180)
			(size 1.5 1.5)
			(drill 0.9)
			(layers "*.Cu" "*.Mask")
			(remove_unused_layers no)
			(net "+3.3V")
		)
		(pad "2" thru_hole circle
			(at 2.54 0 180)
			(size 1.5 1.5)
			(drill 0.9)
			(layers "*.Cu" "*.Mask")
			(remove_unused_layers no)
			(net "GND")
			(thermal_bridge_angle 90)
		)
		(pad "3" thru_hole circle
			(at 5.08 0 180)
			(size 1.5 1.5)
			(drill 0.9)
			(layers "*.Cu" "*.Mask")
			(remove_unused_layers no)
			(net "SCL")
			(thermal_bridge_angle 90)
		)
		(pad "4" thru_hole circle
			(at 7.62 0 180)
			(size 1.5 1.5)
			(drill 0.9)
			(layers "*.Cu" "*.Mask")
			(remove_unused_layers no)
			(net "SDA")
			(thermal_bridge_angle 90)
		)
	)
	(footprint "SamacSys:155124M173200"
		(layer "F.Cu")
		(at 58.4511 101.4162 90)
		(property "Reference" "D15"
			(at -0.4714 1.701931 90)
			(unlocked yes)
			(layer "F.SilkS")
			(effects
				(font
					(size 0.762 0.762)
					(thickness 0.2286)
				)
			)
		)
		(property "Value" "155124M173200"
			(at 7.1725 2.632202 90)
			(unlocked yes)
			(layer "F.SilkS")
			(hide yes)
			(effects
				(font
					(size 1.524 1.524)
					(thickness 0.254)
				)
			)
		)
		(sheetname "USER_IO_STATUS")
		(sheetfile "USER_IO_STATUS.kicad_sch")
		(duplicate_pad_numbers_are_jumpers no)
		(fp_line
			(start -0.8 0.5)
			(end 0.8 0.5)
			(stroke
				(width 0.1)
				(type solid)
			)
			(layer "F.SilkS")
		)
		(fp_arc
			(start -2 -0.1)
			(mid -1.95 -0.05)
			(end -2 0)
			(stroke
				(width 0.1)
				(type solid)
			)
			(layer "F.SilkS")
		)
		(fp_arc
			(start -2 0)
			(mid -2.05 -0.05)
			(end -2 -0.1)
			(stroke
				(width 0.1)
				(type solid)
			)
			(layer "F.SilkS")
		)
		(pad "1" smd rect
			(at -1.4 0 180)
			(size 0.9 0.6)
			(layers "F.Cu" "F.Mask" "F.Paste")
			(net "+3.3V")
		)
		(pad "2" smd rect
			(at -0.45 -0.325 90)
			(size 0.6 0.55)
			(layers "F.Cu" "F.Mask" "F.Paste")
			(net "NetD15_2")
		)
		(pad "3" smd rect
			(at 0.45 -0.325 90)
			(size 0.6 0.55)
			(layers "F.Cu" "F.Mask" "F.Paste")
			(net "NetD15_3")
		)
		(pad "4" smd rect
			(at 1.4 0 180)
			(size 0.9 0.6)
			(layers "F.Cu" "F.Mask" "F.Paste")
			(net "NetD15_4")
		)
	)
	(footprint "Vault:RESC1608X55X25NL10T15"
		(layer "F.Cu")
		(at 77.6261 95.1162 180)
		(property "Reference" "R25"
			(at -0.2286 1.223079 0)
			(unlocked yes)
			(layer "F.SilkS")
			(effects
				(font
					(size 0.762 0.762)
					(thickness 0.2286)
				)
			)
		)
		(property "Value" "49.9R"
			(at -2.911602 3.21199 90)
			(unlocked yes)
			(layer "F.SilkS")
			(hide yes)
			(effects
				(font
					(size 1.524 1.524)
					(thickness 0.254)
				)
			)
		)
		(sheetname "USER_IO")
		(sheetfile "USER_IO.kicad_sch")
		(duplicate_pad_numbers_are_jumpers no)
		(pad "1" smd rect
			(at -0.7 0 270)
			(size 0.9 0.7)
			(layers "F.Cu" "F.Mask" "F.Paste")
			(net "NetR25_1")
		)
		(pad "2" smd rect
			(at 0.7 0 270)
			(size 0.9 0.7)
			(layers "F.Cu" "F.Mask" "F.Paste")
			(net "NetAN1_1")
		)
	)
	(footprint "Vault:RESC1608X55X25NL10T15"
		(layer "F.Cu")
		(at 129.17888 88.71463 180)
		(property "Reference" "R42"
			(at -2.87582 -0.328501 0)
			(unlocked yes)
			(layer "F.SilkS")
			(effects
				(font
					(size 0.762 0.762)
					(thickness 0.2286)
				)
			)
		)
		(property "Value" "DNI_49.9R"
			(at -2.911602 6.132045 90)
			(unlocked yes)
			(layer "F.SilkS")
			(hide yes)
			(effects
				(font
					(size 1.524 1.524)
					(thickness 0.254)
				)
			)
		)
		(sheetname "MAC")
		(sheetfile "MAC.kicad_sch")
		(duplicate_pad_numbers_are_jumpers no)
		(pad "1" smd rect
			(at -0.7 0 270)
			(size 0.9 0.7)
			(layers "F.Cu" "F.Mask" "F.Paste")
			(net "FPGA_MAC_PPS_IN0-")
		)
		(pad "2" smd rect
			(at 0.7 0 270)
			(size 0.9 0.7)
			(layers "F.Cu" "F.Mask" "F.Paste")
			(net "MAC_PPS_IN")
		)
	)
	(footprint "Resistors:RESC1608X50N"
		(layer "F.Cu")
		(at 201.1277 87.7312 180)
		(property "Reference" "R3"
			(at 2.864 -0.428345 0)
			(unlocked yes)
			(layer "F.SilkS")
			(effects
				(font
					(size 0.762 0.762)
					(thickness 0.2286)
				)
				(justify left bottom)
			)
		)
		(property "Value" "ERJ-3EKF4702V"
			(at -18.0821 -3.85659 0)
			(unlocked yes)
			(layer "F.SilkS")
			(hide yes)
			(effects
				(font
					(size 1.524 1.524)
					(thickness 0.254)
				)
				(justify left bottom)
			)
		)
		(sheetname "POWER")
		(sheetfile "POWER.kicad_sch")
		(duplicate_pad_numbers_are_jumpers no)
		(fp_line
			(start 0 -0.5)
			(end 0 0.5)
			(stroke
				(width 0.1524)
				(type solid)
			)
			(layer "F.SilkS")
		)
		(pad "1" smd rect
			(at -0.69 0 270)
			(size 1 0.72)
			(layers "F.Cu" "F.Mask" "F.Paste")
			(net "NetR3_1")
		)
		(pad "2" smd rect
			(at 0.69 0 270)
			(size 1 0.72)
			(layers "F.Cu" "F.Mask" "F.Paste")
			(net "+12V")
		)
	)
	(footprint "Vault:FP-BMX160-MFG"
		(layer "F.Cu")
		(at 186.6261 86.8286)
		(property "Reference" "U13"
			(at -0.7714 -2.723079 0)
			(unlocked yes)
			(layer "F.SilkS")
			(effects
				(font
					(size 0.762 0.762)
					(thickness 0.2286)
				)
			)
		)
		(property "Value" "BMX160"
			(at 1.967145 3.521202 0)
			(unlocked yes)
			(layer "F.SilkS")
			(hide yes)
			(effects
				(font
					(size 1.524 1.524)
					(thickness 0.254)
				)
			)
		)
		(sheetname "GPS_IMU_SENSORS")
		(sheetfile "GPS_IMU_SENSORS.kicad_sch")
		(duplicate_pad_numbers_are_jumpers no)
		(fp_line
			(start -2.1 -1.85)
			(end 2.1 -1.85)
			(stroke
				(width 0.2)
				(type solid)
			)
			(layer "F.SilkS")
		)
		(fp_line
			(start -2.1 1.85)
			(end -2.1 -1.85)
			(stroke
				(width 0.2)
				(type solid)
			)
			(layer "F.SilkS")
		)
		(fp_line
			(start -2.1 1.85)
			(end 2.1 1.85)
			(stroke
				(width 0.2)
				(type solid)
			)
			(layer "F.SilkS")
		)
		(fp_line
			(start 2.1 1.85)
			(end 2.1 -1.85)
			(stroke
				(width 0.2)
				(type solid)
			)
			(layer "F.SilkS")
		)
		(fp_circle
			(center -2.475 -0.75)
			(end -2.475 -0.875)
			(stroke
				(width 0.25)
				(type solid)
			)
			(fill no)
			(layer "F.SilkS")
		)
		(fp_line
			(start -2.1 -1.85)
			(end 2.1 -1.85)
			(stroke
				(width 0.2)
				(type solid)
			)
			(layer "F.CrtYd")
		)
		(fp_line
			(start -2.1 1.85)
			(end -2.1 -1.85)
			(stroke
				(width 0.2)
				(type solid)
			)
			(layer "F.CrtYd")
		)
		(fp_line
			(start -2.1 1.85)
			(end 2.1 1.85)
			(stroke
				(width 0.2)
				(type solid)
			)
			(layer "F.CrtYd")
		)
		(fp_line
			(start 2.1 1.85)
			(end 2.1 -1.85)
			(stroke
				(width 0.2)
				(type solid)
			)
			(layer "F.CrtYd")
		)
		(fp_line
			(start -2.1 -1.85)
			(end 2.1 -1.85)
			(stroke
				(width 0.2)
				(type solid)
			)
			(layer "F.Fab")
		)
		(fp_line
			(start -2.1 1.85)
			(end -2.1 -1.85)
			(stroke
				(width 0.2)
				(type solid)
			)
			(layer "F.Fab")
		)
		(fp_line
			(start -2.1 1.85)
			(end 2.1 1.85)
			(stroke
				(width 0.2)
				(type solid)
			)
			(layer "F.Fab")
		)
		(fp_line
			(start -0.5 0)
			(end 0.5 0)
			(stroke
				(width 0.1)
				(type solid)
			)
			(layer "F.Fab")
		)
		(fp_line
			(start 0 0.5)
			(end 0 -0.5)
			(stroke
				(width 0.1)
				(type solid)
			)
			(layer "F.Fab")
		)
		(fp_line
			(start 2.1 1.85)
			(end 2.1 -1.85)
			(stroke
				(width 0.2)
				(type solid)
			)
			(layer "F.Fab")
		)
		(fp_text user "${REFERENCE}"
			(at -0.00001 0.09602 0)
			(unlocked yes)
			(layer "F.Fab")
			(effects
				(font
					(face "Arial")
					(size 0.63 0.63)
					(thickness 0.1)
				)
				(justify left bottom)
			)
		)
		(pad "1" smd rect
			(at -1.2625 -0.75)
			(size 0.675 0.25)
			(layers "F.Cu" "F.Mask" "F.Paste")
			(net "GND")
			(solder_mask_margin 0)
			(solder_paste_margin 0)
		)
		(pad "2" smd rect
			(at -1.2625 -0.25)
			(size 0.675 0.25)
			(layers "F.Cu" "F.Mask" "F.Paste")
			(net "GND")
			(solder_mask_margin 0)
			(solder_paste_margin 0)
		)
		(pad "3" smd rect
			(at -1.2625 0.25)
			(size 0.675 0.25)
			(layers "F.Cu" "F.Mask" "F.Paste")
			(net "GND")
			(solder_mask_margin 0)
			(solder_paste_margin 0)
		)
		(pad "4" smd rect
			(at -1.2625 0.75)
			(size 0.675 0.25)
			(layers "F.Cu" "F.Mask" "F.Paste")
			(solder_mask_margin 0)
			(solder_paste_margin 0)
		)
		(pad "5" smd rect
			(at -0.5 1.0125)
			(size 0.25 0.675)
			(layers "F.Cu" "F.Mask" "F.Paste")
			(net "+3.3V")
			(solder_mask_margin 0)
			(solder_paste_margin 0)
		)
		(pad "6" smd rect
			(at 0 1.0125)
			(size 0.25 0.675)
			(layers "F.Cu" "F.Mask" "F.Paste")
			(net "GND")
			(solder_mask_margin 0)
			(solder_paste_margin 0)
		)
		(pad "7" smd rect
			(at 0.5 1.0125)
			(size 0.25 0.675)
			(layers "F.Cu" "F.Mask" "F.Paste")
			(net "GND")
			(solder_mask_margin 0)
			(solder_paste_margin 0)
		)
		(pad "8" smd rect
			(at 1.2625 0.75)
			(size 0.675 0.25)
			(layers "F.Cu" "F.Mask" "F.Paste")
			(net "+3.3V")
			(solder_mask_margin 0)
			(solder_paste_margin 0)
		)
		(pad "9" smd rect
			(at 1.2625 0.25)
			(size 0.675 0.25)
			(layers "F.Cu" "F.Mask" "F.Paste")
			(solder_mask_margin 0)
			(solder_paste_margin 0)
		)
		(pad "10" smd rect
			(at 1.2625 -0.25)
			(size 0.675 0.25)
			(layers "F.Cu" "F.Mask" "F.Paste")
			(solder_mask_margin 0)
			(solder_paste_margin 0)
		)
		(pad "11" smd rect
			(at 1.2625 -0.75)
			(size 0.675 0.25)
			(layers "F.Cu" "F.Mask" "F.Paste")
			(solder_mask_margin 0)
			(solder_paste_margin 0)
		)
		(pad "12" smd rect
			(at 0.5 -1.0125)
			(size 0.25 0.675)
			(layers "F.Cu" "F.Mask" "F.Paste")
			(net "+3.3V")
			(solder_mask_margin 0)
			(solder_paste_margin 0)
		)
		(pad "13" smd rect
			(at 0 -1.0125)
			(size 0.25 0.675)
			(layers "F.Cu" "F.Mask" "F.Paste")
			(net "SCL")
			(solder_mask_margin 0)
			(solder_paste_margin 0)
		)
		(pad "14" smd rect
			(at -0.5 -1.0125)
			(size 0.25 0.675)
			(layers "F.Cu" "F.Mask" "F.Paste")
			(net "SDA")
			(solder_mask_margin 0)
			(solder_paste_margin 0)
		)
	)
	(footprint "Vault:TECO-1909763-1_V"
		(layer "F.Cu")
		(at 74.3761 135.6162 -90)
		(property "Reference" "J4"
			(at -2.723079 1.021395 0)
			(unlocked yes)
			(layer "F.SilkS")
			(effects
				(font
					(size 0.762 0.762)
					(thickness 0.2286)
				)
			)
		)
		(property "Value" "1909763-1"
			(at 4.608085 3.749802 270)
			(unlocked yes)
			(layer "F.SilkS")
			(hide yes)
			(effects
				(font
					(size 1.524 1.524)
					(thickness 0.254)
				)
			)
		)
		(sheetname "USER_IO")
		(sheetfile "USER_IO.kicad_sch")
		(duplicate_pad_numbers_are_jumpers no)
		(fp_line
			(start 0.55 -1.3)
			(end -0.55 -1.3)
			(stroke
				(width 0.2)
				(type solid)
			)
			(layer "F.SilkS")
		)
		(fp_circle
			(center -1.778 1.65)
			(end -1.903 1.65)
			(stroke
				(width 0.25)
				(type solid)
			)
			(fill no)
			(layer "F.SilkS")
		)
		(pad "1" smd rect
			(at -1.475 0 270)
			(size 1.05 2.2)
			(layers "F.Cu" "F.Mask" "F.Paste")
			(net "GND")
		)
		(pad "2" smd rect
			(at 0 1.525 270)
			(size 1 1.05)
			(layers "F.Cu" "F.Mask" "F.Paste")
			(net "NetAN4_1")
		)
		(pad "3" smd rect
			(at 1.475 0 270)
			(size 1.05 2.2)
			(layers "F.Cu" "F.Mask" "F.Paste")
			(net "GND")
		)
	)
	(footprint "Vault:CAPC1608X87X45ML20T05"
		(layer "F.Cu")
		(at 186.1761 90.0786 180)
		(property "Reference" "C32"
			(at 3.0714 -0.026921 0)
			(unlocked yes)
			(layer "F.SilkS")
			(effects
				(font
					(size 0.762 0.762)
					(thickness 0.2286)
				)
			)
		)
		(property "Value" "0.1uF"
			(at 2.09443 2.657602 180)
			(unlocked yes)
			(layer "F.SilkS")
			(hide yes)
			(effects
				(font
					(size 1.524 1.524)
					(thickness 0.254)
				)
			)
		)
		(sheetname "GPS_IMU_SENSORS")
		(sheetfile "GPS_IMU_SENSORS.kicad_sch")
		(duplicate_pad_numbers_are_jumpers no)
		(pad "1" smd rect
			(at -0.7 0 270)
			(size 1.1 1.05)
			(layers "F.Cu" "F.Mask" "F.Paste")
			(net "GND")
		)
		(pad "2" smd rect
			(at 0.7 0 270)
			(size 1.1 1.05)
			(layers "F.Cu" "F.Mask" "F.Paste")
			(net "+3.3V")
		)
	)
	(footprint "Vault:CAPC1608X87X45ML20T05"
		(layer "F.Cu")
		(at 212.0765 116.3062 90)
		(property "Reference" "C18"
			(at 1.74 0.905345 90)
			(unlocked yes)
			(layer "F.SilkS")
			(effects
				(font
					(size 0.762 0.762)
					(thickness 0.2286)
				)
				(justify left bottom)
			)
		)
		(property "Value" "0.1uF"
			(at -6.58639 2.8695 0)
			(unlocked yes)
			(layer "F.SilkS")
			(hide yes)
			(effects
				(font
					(size 1.524 1.524)
					(thickness 0.254)
				)
				(justify left bottom)
			)
		)
		(sheetname "POWER")
		(sheetfile "POWER.kicad_sch")
		(duplicate_pad_numbers_are_jumpers no)
		(pad "1" smd rect
			(at -0.7 0 180)
			(size 1.1 1.05)
			(layers "F.Cu" "F.Mask" "F.Paste")
			(net "GND")
		)
		(pad "2" smd rect
			(at 0.7 0 180)
			(size 1.1 1.05)
			(layers "F.Cu" "F.Mask" "F.Paste")
			(net "+5.0V")
		)
	)
	(footprint "Vault:CAPC1608X87X45ML20T05"
		(layer "F.Cu")
		(at 82.39059 84.0062 -90)
		(property "Reference" "C39"
			(at -0.1186 2.987559 90)
			(unlocked yes)
			(layer "F.SilkS")
			(effects
				(font
					(size 0.762 0.762)
					(thickness 0.2286)
				)
			)
		)
		(property "Value" "0.1uF"
			(at 2.09443 2.657592 270)
			(unlocked yes)
			(layer "F.SilkS")
			(hide yes)
			(effects
				(font
					(size 1.524 1.524)
					(thickness 0.254)
				)
			)
		)
		(sheetname "USER_IO_STATUS")
		(sheetfile "USER_IO_STATUS.kicad_sch")
		(duplicate_pad_numbers_are_jumpers no)
		(pad "1" smd rect
			(at -0.7 0)
			(size 1.1 1.05)
			(layers "F.Cu" "F.Mask" "F.Paste")
			(net "GND")
		)
		(pad "2" smd rect
			(at 0.7 0)
			(size 1.1 1.05)
			(layers "F.Cu" "F.Mask" "F.Paste")
			(net "NetC39_2")
		)
	)
	(footprint "Resistors:RESC1608X50N"
		(layer "F.Cu")
		(at 208.8637 90.3662 90)
		(property "Reference" "R7"
			(at 3.982 -0.350345 270)
			(unlocked yes)
			(layer "F.SilkS")
			(effects
				(font
					(size 0.762 0.762)
					(thickness 0.2286)
				)
				(justify left bottom)
			)
		)
		(property "Value" "ERJ-3EKF1002V"
			(at -8.47159 7.6471 0)
			(unlocked yes)
			(layer "F.SilkS")
			(hide yes)
			(effects
				(font
					(size 1.524 1.524)
					(thickness 0.254)
				)
				(justify left bottom)
			)
		)
		(sheetname "POWER")
		(sheetfile "POWER.kicad_sch")
		(duplicate_pad_numbers_are_jumpers no)
		(fp_line
			(start 0 -0.5)
			(end 0 0.5)
			(stroke
				(width 0.1524)
				(type solid)
			)
			(layer "F.SilkS")
		)
		(pad "1" smd rect
			(at -0.69 0 180)
			(size 1 0.72)
			(layers "F.Cu" "F.Mask" "F.Paste")
			(net "GND")
		)
		(pad "2" smd rect
			(at 0.69 0 180)
			(size 1 0.72)
			(layers "F.Cu" "F.Mask" "F.Paste")
			(net "NetR5_1")
		)
	)
	(footprint "Vault:RESC3116X65X50ML20T20"
		(layer "F.Cu")
		(at 155.8261 86.8162)
		(property "Reference" "R45"
			(at 2.7286 -2.273079 0)
			(unlocked yes)
			(layer "F.SilkS")
			(effects
				(font
					(size 0.762 0.762)
					(thickness 0.2286)
				)
			)
		)
		(property "Value" "0_5%_1206"
			(at 4.379365 3.318002 0)
			(unlocked yes)
			(layer "F.SilkS")
			(hide yes)
			(effects
				(font
					(size 1.524 1.524)
					(thickness 0.254)
				)
			)
		)
		(sheetname "MAC")
		(sheetfile "MAC.kicad_sch")
		(duplicate_pad_numbers_are_jumpers no)
		(fp_line
			(start -0.35001 -0.85)
			(end 0.35 -0.85)
			(stroke
				(width 0.2)
				(type solid)
			)
			(layer "F.SilkS")
		)
		(fp_line
			(start -0.35001 0.85)
			(end 0.35 0.85)
			(stroke
				(width 0.2)
				(type solid)
			)
			(layer "F.SilkS")
		)
		(pad "1" smd rect
			(at -1.475 0 90)
			(size 1.9 1.45)
			(layers "F.Cu" "F.Mask" "F.Paste")
			(net "MAC_VCC")
		)
		(pad "2" smd rect
			(at 1.475 0 90)
			(size 1.9 1.45)
			(layers "F.Cu" "F.Mask" "F.Paste")
			(net "+5.0V")
		)
	)
	(footprint "Capacitors:CAPC1608X10N"
		(layer "F.Cu")
		(at 206.7425 119.8622)
		(property "Reference" "C4"
			(at 0.4836 1.360655 180)
			(unlocked yes)
			(layer "F.SilkS")
			(effects
				(font
					(size 0.762 0.762)
					(thickness 0.2286)
				)
				(justify left bottom)
			)
		)
		(property "Value" "CAP_0603_0.01UF_50V"
			(at -3.1503 -8.98381 0)
			(unlocked yes)
			(layer "F.SilkS")
			(hide yes)
			(effects
				(font
					(size 1.524 1.524)
					(thickness 0.254)
				)
				(justify left bottom)
			)
		)
		(sheetname "POWER")
		(sheetfile "POWER.kicad_sch")
		(duplicate_pad_numbers_are_jumpers no)
		(fp_line
			(start -0.635 -0.7112)
			(end 0.635 -0.7112)
			(stroke
				(width 0.1524)
				(type solid)
			)
			(layer "F.SilkS")
		)
		(fp_line
			(start -0.635 0.7112)
			(end 0.635 0.7112)
			(stroke
				(width 0.1524)
				(type solid)
			)
			(layer "F.SilkS")
		)
		(pad "1" smd rect
			(at -0.8 0 90)
			(size 0.95 1)
			(layers "F.Cu" "F.Mask" "F.Paste")
			(net "NetC4_1")
		)
		(pad "2" smd rect
			(at 0.8 0 90)
			(size 0.95 1)
			(layers "F.Cu" "F.Mask" "F.Paste")
			(net "NetC4_2")
		)
	)
)
